(kicad_pcb
	(version 20260206)
	(generator "pcbnew")
	(generator_version "10.0")
	(general
		(thickness 1.6)
		(legacy_teardrops no)
	)
	(paper "A4")
	(title_block
		(title "Bryce Canyon_SCC_16316-1_OCP.brd")
		(comment 1 "Bryce Canyon / footprint 146 of 1561 (CN2), pads 73-147 of 342")
	)
	(layers
		(0 "F.Cu" signal "TOP")
		(4 "In1.Cu" signal "L2GND")
		(6 "In2.Cu" signal "L3")
		(8 "In3.Cu" signal "L4VCC")
		(10 "In4.Cu" signal "L5VCC")
		(12 "In5.Cu" signal "L6")
		(14 "In6.Cu" signal "L7GND")
		(2 "B.Cu" signal "BOTTOM")
		(9 "F.Adhes" user "F.Adhesive")
		(11 "B.Adhes" user "B.Adhesive")
		(13 "F.Paste" user "Package Geometry/Pastemask Top")
		(15 "B.Paste" user "Package Geometry/Pastemask Bottom")
		(5 "F.SilkS" user "Ref Des/Silkscreen Top")
		(7 "B.SilkS" user "Ref Des/Silkscreen Bottom")
		(1 "F.Mask" user "Board Geometry/Soldermask Top")
		(3 "B.Mask" user "Board Geometry/Soldermask Bottom")
		(17 "Dwgs.User" user "User.Drawings")
		(19 "Cmts.User" user "User.Comments")
		(21 "Eco1.User" user "User.Eco1")
		(23 "Eco2.User" user "User.Eco2")
		(25 "Edge.Cuts" user "Board Geometry/Outline")
		(27 "Margin" user)
		(31 "F.CrtYd" user "Package Geometry/Place Bound Top")
		(29 "B.CrtYd" user "Package Geometry/Place Bound Bottom")
		(35 "F.Fab" user "Ref Des/Assembly Top")
		(33 "B.Fab" user "Ref Des/Assembly Bottom")
	)
	(footprint ""
		(layer "F.Cu")
		(at 86.000082 -3.800094)
		(property "Reference" "CN2"
			(at 0 0 0)
			(layer "F.SilkS")
			(hide yes)
			(effects
				(font
					(size 1.27 1.27)
				)
			)
		)
		(property "Value" "AMP-CONN342-10R-3-GP"
			(at -12.8905 -12.5222 0)
			(unlocked yes)
			(layer "F.Fab")
			(hide yes)
			(effects
				(font
					(size 1.016 1.016)
					(thickness 0.1524)
				)
			)
		)
		(property "Device Type" "PREFIT-342P-648260H400"
			(at -12.8905 -14.0462 0)
			(unlocked yes)
			(layer "F.Fab")
			(hide yes)
			(effects
				(font
					(size 1.016 1.016)
					(thickness 0.1524)
				)
			)
		)
		(duplicate_pad_numbers_are_jumpers no)
		(pad "C1" thru_hole circle
			(at 0 -3.599942)
			(size 0.762 0.762)
			(drill 0.359918)
			(layers "*.Cu" "*.Mask")
			(remove_unused_layers no)
			(net "SCC_STBY_PGOOD")
			(clearance 0.1651)
			(thermal_gap 0.1651)
		)
		(pad "C2" thru_hole circle
			(at 1.800098 -2.400046)
			(size 0.762 0.762)
			(drill 0.359918)
			(layers "*.Cu" "*.Mask")
			(remove_unused_layers no)
			(net "P3V3_DPB")
			(clearance 0.1651)
			(thermal_gap 0.1651)
		)
		(pad "C3" thru_hole circle
			(at 3.599942 -3.599942)
			(size 0.762 0.762)
			(drill 0.359918)
			(layers "*.Cu" "*.Mask")
			(remove_unused_layers no)
			(net "SCC_LOC_HEARTBEAT")
			(clearance 0.1651)
			(thermal_gap 0.1651)
		)
		(pad "C4" thru_hole circle
			(at 5.40004 -2.400046)
			(size 0.762 0.762)
			(drill 0.359918)
			(layers "*.Cu" "*.Mask")
			(remove_unused_layers no)
			(net "SLOT_ID_0")
			(clearance 0.1651)
			(thermal_gap 0.1651)
		)
		(pad "C5" thru_hole circle
			(at 7.199884 -3.599942)
			(size 0.762 0.762)
			(drill 0.359918)
			(layers "*.Cu" "*.Mask")
			(remove_unused_layers no)
			(net "SCC_TYPE_0")
			(clearance 0.1651)
			(thermal_gap 0.1651)
		)
		(pad "C6" thru_hole circle
			(at 8.999982 -2.400046)
			(size 0.762 0.762)
			(drill 0.359918)
			(layers "*.Cu" "*.Mask")
			(remove_unused_layers no)
			(net "SCC_TYPE_2")
			(clearance 0.1651)
			(thermal_gap 0.1651)
		)
		(pad "C7" thru_hole circle
			(at 10.80008 -3.599942)
			(size 0.762 0.762)
			(drill 0.359918)
			(layers "*.Cu" "*.Mask")
			(remove_unused_layers no)
			(net "UART_SDB_TX")
			(clearance 0.1651)
			(thermal_gap 0.1651)
		)
		(pad "C8" thru_hole circle
			(at 12.599924 -2.400046)
			(size 0.762 0.762)
			(drill 0.359918)
			(layers "*.Cu" "*.Mask")
			(remove_unused_layers no)
			(net "PWM_OUT_ZONE_C")
			(clearance 0.1651)
			(thermal_gap 0.1651)
		)
		(pad "C9" thru_hole circle
			(at 14.400022 -3.599942)
			(size 0.762 0.762)
			(drill 0.359918)
			(layers "*.Cu" "*.Mask")
			(remove_unused_layers no)
			(net "SYS_PWR_LED_N")
			(clearance 0.1651)
			(thermal_gap 0.1651)
		)
		(pad "C10" thru_hole circle
			(at 16.20012 -2.400046)
			(size 0.762 0.762)
			(drill 0.359918)
			(layers "*.Cu" "*.Mask")
			(remove_unused_layers no)
			(net "ENCL_FAULT_LED")
			(clearance 0.1651)
			(thermal_gap 0.1651)
		)
		(pad "C11" thru_hole circle
			(at 17.999964 -3.599942)
			(size 0.762 0.762)
			(drill 0.359918)
			(layers "*.Cu" "*.Mask")
			(remove_unused_layers no)
			(net "DRIVE_INSERT_ALERT_N")
			(clearance 0.1651)
			(thermal_gap 0.1651)
		)
		(pad "C12" thru_hole circle
			(at 19.800062 -2.400046)
			(size 0.762 0.762)
			(drill 0.359918)
			(layers "*.Cu" "*.Mask")
			(remove_unused_layers no)
			(net "I2C_CLIP_SCL7")
			(clearance 0.1651)
			(thermal_gap 0.1651)
		)
		(pad "C13" thru_hole circle
			(at 21.599906 -3.599942)
			(size 0.762 0.762)
			(drill 0.359918)
			(layers "*.Cu" "*.Mask")
			(remove_unused_layers no)
			(net "UART_EXP_TX")
			(clearance 0.1651)
			(thermal_gap 0.1651)
		)
		(pad "C14" thru_hole circle
			(at 23.400004 -2.400046)
			(size 0.762 0.762)
			(drill 0.359918)
			(layers "*.Cu" "*.Mask")
			(remove_unused_layers no)
			(net "I2C_DPB_SCL3")
			(clearance 0.1651)
			(thermal_gap 0.1651)
		)
		(pad "C15" thru_hole circle
			(at 25.200102 -3.599942)
			(size 0.762 0.762)
			(drill 0.359918)
			(layers "*.Cu" "*.Mask")
			(remove_unused_layers no)
			(net "I2C_DRIVE_PWR_SCL4")
			(clearance 0.1651)
			(thermal_gap 0.1651)
		)
		(pad "C16" thru_hole circle
			(at 26.999946 -2.400046)
			(size 0.762 0.762)
			(drill 0.359918)
			(layers "*.Cu" "*.Mask")
			(remove_unused_layers no)
			(net "I2C_DRIVE_INS_SCL5")
			(clearance 0.1651)
			(thermal_gap 0.1651)
		)
		(pad "C17" thru_hole circle
			(at 28.800044 -3.599942)
			(size 0.762 0.762)
			(drill 0.359918)
			(layers "*.Cu" "*.Mask")
			(remove_unused_layers no)
			(net "I2C_DRIVE_FLT_LED_SCL6")
			(clearance 0.1651)
			(thermal_gap 0.1651)
		)
		(pad "C18" thru_hole circle
			(at 30.599888 -2.400046)
			(size 0.762 0.762)
			(drill 0.359918)
			(layers "*.Cu" "*.Mask")
			(remove_unused_layers no)
			(net "DRIVE_0_ACT")
			(clearance 0.1651)
			(thermal_gap 0.1651)
		)
		(pad "C19" thru_hole circle
			(at 32.399986 -3.599942)
			(size 0.762 0.762)
			(drill 0.359918)
			(layers "*.Cu" "*.Mask")
			(remove_unused_layers no)
			(net "DRIVE_2_ACT")
			(clearance 0.1651)
			(thermal_gap 0.1651)
		)
		(pad "C20" thru_hole circle
			(at 34.200084 -2.400046)
			(size 0.762 0.762)
			(drill 0.359918)
			(layers "*.Cu" "*.Mask")
			(remove_unused_layers no)
			(net "DRIVE_4_ACT")
			(clearance 0.1651)
			(thermal_gap 0.1651)
		)
		(pad "C21" thru_hole circle
			(at 35.999928 -3.599942)
			(size 0.762 0.762)
			(drill 0.359918)
			(layers "*.Cu" "*.Mask")
			(remove_unused_layers no)
			(net "DRIVE_6_ACT")
			(clearance 0.1651)
			(thermal_gap 0.1651)
		)
		(pad "C22" thru_hole circle
			(at 37.800026 -2.400046)
			(size 0.762 0.762)
			(drill 0.359918)
			(layers "*.Cu" "*.Mask")
			(remove_unused_layers no)
			(net "DRIVE_12_ACT")
			(clearance 0.1651)
			(thermal_gap 0.1651)
		)
		(pad "C23" thru_hole circle
			(at 39.600124 -3.599942)
			(size 0.762 0.762)
			(drill 0.359918)
			(layers "*.Cu" "*.Mask")
			(remove_unused_layers no)
			(net "DRIVE_14_ACT")
			(clearance 0.1651)
			(thermal_gap 0.1651)
		)
		(pad "C24" thru_hole circle
			(at 41.399968 -2.400046)
			(size 0.762 0.762)
			(drill 0.359918)
			(layers "*.Cu" "*.Mask")
			(remove_unused_layers no)
			(net "DRIVE_16_ACT")
			(clearance 0.1651)
			(thermal_gap 0.1651)
		)
		(pad "C25" thru_hole circle
			(at 43.200066 -3.599942)
			(size 0.762 0.762)
			(drill 0.359918)
			(layers "*.Cu" "*.Mask")
			(remove_unused_layers no)
			(net "DRIVE_18_ACT")
			(clearance 0.1651)
			(thermal_gap 0.1651)
		)
		(pad "C26" thru_hole circle
			(at 44.99991 -2.400046)
			(size 0.762 0.762)
			(drill 0.359918)
			(layers "*.Cu" "*.Mask")
			(remove_unused_layers no)
			(net "DRIVE_20_ACT")
			(clearance 0.1651)
			(thermal_gap 0.1651)
		)
		(pad "C27" thru_hole circle
			(at 46.800008 -3.599942)
			(size 0.762 0.762)
			(drill 0.359918)
			(layers "*.Cu" "*.Mask")
			(remove_unused_layers no)
			(net "DRIVE_22_ACT")
			(clearance 0.1651)
			(thermal_gap 0.1651)
		)
		(pad "C28" thru_hole circle
			(at 48.600106 -2.400046)
			(size 0.762 0.762)
			(drill 0.359918)
			(layers "*.Cu" "*.Mask")
			(remove_unused_layers no)
			(net "DRIVE_24_ACT")
			(clearance 0.1651)
			(thermal_gap 0.1651)
		)
		(pad "C29" thru_hole circle
			(at 50.39995 -3.599942)
			(size 0.762 0.762)
			(drill 0.359918)
			(layers "*.Cu" "*.Mask")
			(remove_unused_layers no)
			(net "DRIVE_26_ACT")
			(clearance 0.1651)
			(thermal_gap 0.1651)
		)
		(pad "C30" thru_hole circle
			(at 52.200048 -2.400046)
			(size 0.762 0.762)
			(drill 0.359918)
			(layers "*.Cu" "*.Mask")
			(remove_unused_layers no)
			(net "DRIVE_28_ACT")
			(clearance 0.1651)
			(thermal_gap 0.1651)
		)
		(pad "C31" thru_hole circle
			(at 53.999892 -3.599942)
			(size 0.762 0.762)
			(drill 0.359918)
			(layers "*.Cu" "*.Mask")
			(remove_unused_layers no)
			(net "DRIVE_30_ACT")
			(clearance 0.1651)
			(thermal_gap 0.1651)
		)
		(pad "C32" thru_hole circle
			(at 55.79999 -2.400046)
			(size 0.762 0.762)
			(drill 0.359918)
			(layers "*.Cu" "*.Mask")
			(remove_unused_layers no)
			(net "DRIVE_32_ACT")
			(clearance 0.1651)
			(thermal_gap 0.1651)
		)
		(pad "C33" thru_hole circle
			(at 57.600088 -3.599942)
			(size 0.762 0.762)
			(drill 0.359918)
			(layers "*.Cu" "*.Mask")
			(remove_unused_layers no)
			(net "DRIVE_34_ACT")
			(clearance 0.1651)
			(thermal_gap 0.1651)
		)
		(pad "C34" thru_hole circle
			(at 59.399932 -2.400046)
			(size 0.762 0.762)
			(drill 0.359918)
			(layers "*.Cu" "*.Mask")
			(remove_unused_layers no)
			(net "DRIVE_36_ACT")
			(clearance 0.1651)
			(thermal_gap 0.1651)
		)
		(pad "C35" thru_hole circle
			(at 61.20003 -3.599942)
			(size 0.762 0.762)
			(drill 0.359918)
			(layers "*.Cu" "*.Mask")
			(remove_unused_layers no)
			(net "DRIVE_38_ACT")
			(clearance 0.1651)
			(thermal_gap 0.1651)
		)
		(pad "C36" thru_hole circle
			(at 62.999874 -2.400046)
			(size 0.762 0.762)
			(drill 0.359918)
			(layers "*.Cu" "*.Mask")
			(remove_unused_layers no)
			(net "SCC_HSC_N")
			(clearance 0.1651)
			(thermal_gap 0.1651)
		)
		(pad "D1" thru_hole circle
			(at 0 -4.99999)
			(size 0.762 0.762)
			(drill 0.359918)
			(layers "*.Cu" "*.Mask")
			(remove_unused_layers no)
			(net "BMC_LOC_HEARTBEAT")
			(clearance 0.1651)
			(thermal_gap 0.1651)
		)
		(pad "D2" thru_hole circle
			(at 1.800098 -3.800094)
			(size 0.762 0.762)
			(drill 0.359918)
			(layers "*.Cu" "*.Mask")
			(remove_unused_layers no)
			(net "SCC_STBY_PWR_EN")
			(clearance 0.1651)
			(thermal_gap 0.1651)
		)
		(pad "D3" thru_hole circle
			(at 3.599942 -4.99999)
			(size 0.762 0.762)
			(drill 0.359918)
			(layers "*.Cu" "*.Mask")
			(remove_unused_layers no)
			(net "SCC_RMT_HEARTBEAT")
			(clearance 0.1651)
			(thermal_gap 0.1651)
		)
		(pad "D4" thru_hole circle
			(at 5.40004 -3.800094)
			(size 0.762 0.762)
			(drill 0.359918)
			(layers "*.Cu" "*.Mask")
			(remove_unused_layers no)
			(net "SLOT_ID_1")
			(clearance 0.1651)
			(thermal_gap 0.1651)
		)
		(pad "D5" thru_hole circle
			(at 7.199884 -4.99999)
			(size 0.762 0.762)
			(drill 0.359918)
			(layers "*.Cu" "*.Mask")
			(remove_unused_layers no)
			(net "SCC_TYPE_1")
			(clearance 0.1651)
			(thermal_gap 0.1651)
		)
		(pad "D6" thru_hole circle
			(at 8.999982 -3.800094)
			(size 0.762 0.762)
			(drill 0.359918)
			(layers "*.Cu" "*.Mask")
			(remove_unused_layers no)
			(net "SCC_TYPE_3")
			(clearance 0.1651)
			(thermal_gap 0.1651)
		)
		(pad "D7" thru_hole circle
			(at 10.80008 -4.99999)
			(size 0.762 0.762)
			(drill 0.359918)
			(layers "*.Cu" "*.Mask")
			(remove_unused_layers no)
			(net "UART_SDB_RX")
			(clearance 0.1651)
			(thermal_gap 0.1651)
		)
		(pad "D8" thru_hole circle
			(at 12.599924 -3.800094)
			(size 0.762 0.762)
			(drill 0.359918)
			(layers "*.Cu" "*.Mask")
			(remove_unused_layers no)
			(net "PWM_OUT_ZONE_D")
			(clearance 0.1651)
			(thermal_gap 0.1651)
		)
		(pad "D9" thru_hole circle
			(at 14.400022 -4.99999)
			(size 0.762 0.762)
			(drill 0.359918)
			(layers "*.Cu" "*.Mask")
			(remove_unused_layers no)
			(net "SCC_FULL_PWR_EN")
			(clearance 0.1651)
			(thermal_gap 0.1651)
		)
		(pad "D10" thru_hole circle
			(at 16.20012 -3.800094)
			(size 0.762 0.762)
			(drill 0.359918)
			(layers "*.Cu" "*.Mask")
			(remove_unused_layers no)
			(net "SCC_RESET_N")
			(clearance 0.1651)
			(thermal_gap 0.1651)
		)
		(pad "D11" thru_hole circle
			(at 17.999964 -4.99999)
			(size 0.762 0.762)
			(drill 0.359918)
			(layers "*.Cu" "*.Mask")
			(remove_unused_layers no)
			(net "SCC_LOC_INS_N")
			(clearance 0.1651)
			(thermal_gap 0.1651)
		)
		(pad "D12" thru_hole circle
			(at 19.800062 -3.800094)
			(size 0.762 0.762)
			(drill 0.359918)
			(layers "*.Cu" "*.Mask")
			(remove_unused_layers no)
			(net "I2C_CLIP_SDA7")
			(clearance 0.1651)
			(thermal_gap 0.1651)
		)
		(pad "D13" thru_hole circle
			(at 21.599906 -4.99999)
			(size 0.762 0.762)
			(drill 0.359918)
			(layers "*.Cu" "*.Mask")
			(remove_unused_layers no)
			(net "UART_EXP_RX")
			(clearance 0.1651)
			(thermal_gap 0.1651)
		)
		(pad "D14" thru_hole circle
			(at 23.400004 -3.800094)
			(size 0.762 0.762)
			(drill 0.359918)
			(layers "*.Cu" "*.Mask")
			(remove_unused_layers no)
			(net "I2C_DPB_SDA3")
			(clearance 0.1651)
			(thermal_gap 0.1651)
		)
		(pad "D15" thru_hole circle
			(at 25.200102 -4.99999)
			(size 0.762 0.762)
			(drill 0.359918)
			(layers "*.Cu" "*.Mask")
			(remove_unused_layers no)
			(net "I2C_DRIVE_PWR_SDA4")
			(clearance 0.1651)
			(thermal_gap 0.1651)
		)
		(pad "D16" thru_hole circle
			(at 26.999946 -3.800094)
			(size 0.762 0.762)
			(drill 0.359918)
			(layers "*.Cu" "*.Mask")
			(remove_unused_layers no)
			(net "I2C_DRIVE_INS_SDA5")
			(clearance 0.1651)
			(thermal_gap 0.1651)
		)
		(pad "D17" thru_hole circle
			(at 28.800044 -4.99999)
			(size 0.762 0.762)
			(drill 0.359918)
			(layers "*.Cu" "*.Mask")
			(remove_unused_layers no)
			(net "I2C_DRIVE_FLT_LED_SDA6")
			(clearance 0.1651)
			(thermal_gap 0.1651)
		)
		(pad "D18" thru_hole circle
			(at 30.599888 -3.800094)
			(size 0.762 0.762)
			(drill 0.359918)
			(layers "*.Cu" "*.Mask")
			(remove_unused_layers no)
			(net "DRIVE_1_ACT")
			(clearance 0.1651)
			(thermal_gap 0.1651)
		)
		(pad "D19" thru_hole circle
			(at 32.399986 -4.99999)
			(size 0.762 0.762)
			(drill 0.359918)
			(layers "*.Cu" "*.Mask")
			(remove_unused_layers no)
			(net "DRIVE_3_ACT")
			(clearance 0.1651)
			(thermal_gap 0.1651)
		)
		(pad "D20" thru_hole circle
			(at 34.200084 -3.800094)
			(size 0.762 0.762)
			(drill 0.359918)
			(layers "*.Cu" "*.Mask")
			(remove_unused_layers no)
			(net "DRIVE_5_ACT")
			(clearance 0.1651)
			(thermal_gap 0.1651)
		)
		(pad "D21" thru_hole circle
			(at 35.999928 -4.99999)
			(size 0.762 0.762)
			(drill 0.359918)
			(layers "*.Cu" "*.Mask")
			(remove_unused_layers no)
			(net "DRIVE_7_ACT")
			(clearance 0.1651)
			(thermal_gap 0.1651)
		)
		(pad "D22" thru_hole circle
			(at 37.800026 -3.800094)
			(size 0.762 0.762)
			(drill 0.359918)
			(layers "*.Cu" "*.Mask")
			(remove_unused_layers no)
			(net "DRIVE_13_ACT")
			(clearance 0.1651)
			(thermal_gap 0.1651)
		)
		(pad "D23" thru_hole circle
			(at 39.600124 -4.99999)
			(size 0.762 0.762)
			(drill 0.359918)
			(layers "*.Cu" "*.Mask")
			(remove_unused_layers no)
			(net "DRIVE_15_ACT")
			(clearance 0.1651)
			(thermal_gap 0.1651)
		)
		(pad "D24" thru_hole circle
			(at 41.399968 -3.800094)
			(size 0.762 0.762)
			(drill 0.359918)
			(layers "*.Cu" "*.Mask")
			(remove_unused_layers no)
			(net "DRIVE_17_ACT")
			(clearance 0.1651)
			(thermal_gap 0.1651)
		)
		(pad "D25" thru_hole circle
			(at 43.200066 -4.99999)
			(size 0.762 0.762)
			(drill 0.359918)
			(layers "*.Cu" "*.Mask")
			(remove_unused_layers no)
			(net "DRIVE_19_ACT")
			(clearance 0.1651)
			(thermal_gap 0.1651)
		)
		(pad "D26" thru_hole circle
			(at 44.99991 -3.800094)
			(size 0.762 0.762)
			(drill 0.359918)
			(layers "*.Cu" "*.Mask")
			(remove_unused_layers no)
			(net "DRIVE_21_ACT")
			(clearance 0.1651)
			(thermal_gap 0.1651)
		)
		(pad "D27" thru_hole circle
			(at 46.800008 -4.99999)
			(size 0.762 0.762)
			(drill 0.359918)
			(layers "*.Cu" "*.Mask")
			(remove_unused_layers no)
			(net "DRIVE_23_ACT")
			(clearance 0.1651)
			(thermal_gap 0.1651)
		)
		(pad "D28" thru_hole circle
			(at 48.600106 -3.800094)
			(size 0.762 0.762)
			(drill 0.359918)
			(layers "*.Cu" "*.Mask")
			(remove_unused_layers no)
			(net "DRIVE_25_ACT")
			(clearance 0.1651)
			(thermal_gap 0.1651)
		)
		(pad "D29" thru_hole circle
			(at 50.39995 -4.99999)
			(size 0.762 0.762)
			(drill 0.359918)
			(layers "*.Cu" "*.Mask")
			(remove_unused_layers no)
			(net "DRIVE_27_ACT")
			(clearance 0.1651)
			(thermal_gap 0.1651)
		)
		(pad "D30" thru_hole circle
			(at 52.200048 -3.800094)
			(size 0.762 0.762)
			(drill 0.359918)
			(layers "*.Cu" "*.Mask")
			(remove_unused_layers no)
			(net "DRIVE_29_ACT")
			(clearance 0.1651)
			(thermal_gap 0.1651)
		)
		(pad "D31" thru_hole circle
			(at 53.999892 -4.99999)
			(size 0.762 0.762)
			(drill 0.359918)
			(layers "*.Cu" "*.Mask")
			(remove_unused_layers no)
			(net "DRIVE_31_ACT")
			(clearance 0.1651)
			(thermal_gap 0.1651)
		)
		(pad "D32" thru_hole circle
			(at 55.79999 -3.800094)
			(size 0.762 0.762)
			(drill 0.359918)
			(layers "*.Cu" "*.Mask")
			(remove_unused_layers no)
			(net "DRIVE_33_ACT")
			(clearance 0.1651)
			(thermal_gap 0.1651)
		)
		(pad "D33" thru_hole circle
			(at 57.600088 -4.99999)
			(size 0.762 0.762)
			(drill 0.359918)
			(layers "*.Cu" "*.Mask")
			(remove_unused_layers no)
			(net "DRIVE_35_ACT")
			(clearance 0.1651)
			(thermal_gap 0.1651)
		)
		(pad "D34" thru_hole circle
			(at 59.399932 -3.800094)
			(size 0.762 0.762)
			(drill 0.359918)
			(layers "*.Cu" "*.Mask")
			(remove_unused_layers no)
			(net "DRIVE_37_ACT")
			(clearance 0.1651)
			(thermal_gap 0.1651)
		)
		(pad "D35" thru_hole circle
			(at 61.20003 -4.99999)
			(size 0.762 0.762)
			(drill 0.359918)
			(layers "*.Cu" "*.Mask")
			(remove_unused_layers no)
			(net "DRIVE_39_ACT")
			(clearance 0.1651)
			(thermal_gap 0.1651)
		)
		(pad "D36" thru_hole circle
			(at 62.999874 -3.800094)
			(size 0.762 0.762)
			(drill 0.359918)
			(layers "*.Cu" "*.Mask")
			(remove_unused_layers no)
			(net "SCC_FULL_PGOOD_BUF")
			(clearance 0.1651)
			(thermal_gap 0.1651)
		)
		(pad "E1" thru_hole circle
			(at 0 -7.199884)
			(size 0.762 0.762)
			(drill 0.359918)
			(layers "*.Cu" "*.Mask")
			(remove_unused_layers no)
			(net "PHY_SCC_TO_DPB_12_DP")
			(clearance 0.1651)
			(thermal_gap 0.1651)
		)
		(pad "E2" thru_hole circle
			(at 1.800098 -5.999988)
			(size 0.762 0.762)
			(drill 0.359918)
			(layers "*.Cu" "*.Mask")
			(remove_unused_layers no)
			(net "PHY_SCC_TO_DPB_13_DP")
			(clearance 0.1651)
			(thermal_gap 0.1651)
		)
		(pad "E3" thru_hole circle
			(at 3.599942 -7.199884)
			(size 0.762 0.762)
			(drill 0.359918)
			(layers "*.Cu" "*.Mask")
			(remove_unused_layers no)
			(net "PHY_SCC_TO_DPB_14_DP")
			(clearance 0.1651)
			(thermal_gap 0.1651)
		)
	)
)
